(kicad_pcb
	(version 20260206)
	(generator "pcbnew")
	(generator_version "10.0")
	(general
		(thickness 1.6)
		(legacy_teardrops no)
	)
	(paper "A4")
	(title_block
		(title "Bryce Canyon_R.DPB_16317-1_OCP.brd")
		(comment 1 "Bryce Canyon / footprints 1917-1923 of 2099")
	)
	(layers
		(0 "F.Cu" signal "TOP")
		(4 "In1.Cu" signal "L2GND")
		(6 "In2.Cu" signal "L3")
		(8 "In3.Cu" signal "L4VCC")
		(10 "In4.Cu" signal "L5VCC")
		(12 "In5.Cu" signal "L6")
		(14 "In6.Cu" signal "L7GND")
		(2 "B.Cu" signal "BOTTOM")
		(9 "F.Adhes" user "F.Adhesive")
		(11 "B.Adhes" user "B.Adhesive")
		(13 "F.Paste" user "Package Geometry/Pastemask Top")
		(15 "B.Paste" user "Package Geometry/Pastemask Bottom")
		(5 "F.SilkS" user "Ref Des/Silkscreen Top")
		(7 "B.SilkS" user "Ref Des/Silkscreen Bottom")
		(1 "F.Mask" user "Board Geometry/Soldermask Top")
		(3 "B.Mask" user "Board Geometry/Soldermask Bottom")
		(17 "Dwgs.User" user "User.Drawings")
		(19 "Cmts.User" user "User.Comments")
		(21 "Eco1.User" user "User.Eco1")
		(23 "Eco2.User" user "User.Eco2")
		(25 "Edge.Cuts" user "Board Geometry/Outline")
		(27 "Margin" user)
		(31 "F.CrtYd" user "Package Geometry/Place Bound Top")
		(29 "B.CrtYd" user "Package Geometry/Place Bound Bottom")
		(35 "F.Fab" user "Ref Des/Assembly Top")
		(33 "B.Fab" user "Ref Des/Assembly Bottom")
	)
	(footprint ""
		(layer "F.Cu")
		(at 335.788 -246.761 180)
		(property "Reference" "R267"
			(at 0 0 180)
			(layer "F.SilkS")
			(hide yes)
			(effects
				(font
					(size 1.27 1.27)
				)
			)
		)
		(property "Value" "0R2J-2-GP"
			(at 0.064008 -3.993896 180)
			(unlocked yes)
			(layer "F.Fab")
			(hide yes)
			(effects
				(font
					(size 1.016 1.016)
					(thickness 0.1524)
				)
			)
		)
		(property "Device Type" "R402H16"
			(at 0.064008 -5.517896 180)
			(unlocked yes)
			(layer "F.Fab")
			(hide yes)
			(effects
				(font
					(size 1.016 1.016)
					(thickness 0.1524)
				)
			)
		)
		(duplicate_pad_numbers_are_jumpers no)
		(fp_line
			(start 0.508 -0.9398)
			(end -0.508 -0.9398)
			(stroke
				(width 0.1524)
				(type default)
			)
			(layer "F.SilkS")
		)
		(fp_line
			(start -0.508 -0.9398)
			(end -0.508 0.9398)
			(stroke
				(width 0.1524)
				(type default)
			)
			(layer "F.SilkS")
		)
		(fp_rect
			(start -0.508 0.9398)
			(end 0.508 -0.9398)
			(stroke
				(width 0)
				(type default)
			)
			(fill no)
			(layer "F.CrtYd")
		)
		(fp_rect
			(start -0.508 0.9398)
			(end 0.508 -0.9398)
			(stroke
				(width 0)
				(type default)
			)
			(fill no)
			(layer "F.Fab")
		)
		(pad "1" smd custom
			(at 0 -0.4445 180)
			(size 0.1397 0.1397)
			(layers "F.Cu" "F.Mask" "F.Paste")
			(net "SW_HDD_G6")
			(options
				(clearance outline)
				(anchor circle)
			)
			(primitives
				(gr_poly
					(pts
						(arc
							(start -0.1778 -0.2794)
							(mid -0.249642 -0.249642)
							(end -0.2794 -0.1778)
						)
						(arc
							(start -0.2794 0.1778)
							(mid -0.249642 0.249642)
							(end -0.1778 0.2794)
						)
						(arc
							(start 0.1778 0.2794)
							(mid 0.249642 0.249642)
							(end 0.2794 0.1778)
						)
						(arc
							(start 0.2794 -0.1778)
							(mid 0.249642 -0.249642)
							(end 0.1778 -0.2794)
						)
					)
					(width 0)
					(fill yes)
				)
			)
		)
		(pad "2" smd custom
			(at 0 0.4445 180)
			(size 0.1397 0.1397)
			(layers "F.Cu" "F.Mask" "F.Paste")
			(net "SW_HDD_R6")
			(options
				(clearance outline)
				(anchor circle)
			)
			(primitives
				(gr_poly
					(pts
						(arc
							(start -0.1778 -0.2794)
							(mid -0.249642 -0.249642)
							(end -0.2794 -0.1778)
						)
						(arc
							(start -0.2794 0.1778)
							(mid -0.249642 0.249642)
							(end -0.1778 0.2794)
						)
						(arc
							(start 0.1778 0.2794)
							(mid 0.249642 0.249642)
							(end 0.2794 0.1778)
						)
						(arc
							(start 0.2794 -0.1778)
							(mid 0.249642 -0.249642)
							(end 0.1778 -0.2794)
						)
					)
					(width 0)
					(fill yes)
				)
			)
		)
	)
	(footprint ""
		(layer "F.Cu")
		(at 35.306 -147.066 90)
		(property "Reference" "C188"
			(at 0 0 90)
			(layer "F.SilkS")
			(hide yes)
			(effects
				(font
					(size 1.27 1.27)
				)
			)
		)
		(property "Value" "SCD01U50V2KX-1GP"
			(at 1.1811 -2.7051 90)
			(unlocked yes)
			(layer "F.Fab")
			(hide yes)
			(effects
				(font
					(size 1.016 1.016)
					(thickness 0.1524)
				)
			)
		)
		(property "Device Type" "C402H22"
			(at 1.1811 -4.2291 90)
			(unlocked yes)
			(layer "F.Fab")
			(hide yes)
			(effects
				(font
					(size 1.016 1.016)
					(thickness 0.1524)
				)
			)
		)
		(duplicate_pad_numbers_are_jumpers no)
		(fp_rect
			(start -0.4318 0.9525)
			(end 0.4318 -0.9525)
			(stroke
				(width 0)
				(type default)
			)
			(fill no)
			(layer "F.CrtYd")
		)
		(fp_rect
			(start -0.4318 0.9525)
			(end 0.4318 -0.9525)
			(stroke
				(width 0)
				(type default)
			)
			(fill no)
			(layer "F.Fab")
		)
		(pad "1" smd custom
			(at 0 -0.4445 90)
			(size 0.1524 0.1524)
			(layers "F.Cu" "F.Mask" "F.Paste")
			(net "HDD_PRSNT_12")
			(options
				(clearance outline)
				(anchor circle)
			)
			(primitives
				(gr_poly
					(pts
						(arc
							(start 0.3048 -0.2032)
							(mid 0.275042 -0.275042)
							(end 0.2032 -0.3048)
						)
						(arc
							(start -0.2032 -0.3048)
							(mid -0.275042 -0.275042)
							(end -0.3048 -0.2032)
						)
						(arc
							(start -0.3048 0.2032)
							(mid -0.275042 0.275042)
							(end -0.2032 0.3048)
						)
						(arc
							(start 0.2032 0.3048)
							(mid 0.275042 0.275042)
							(end 0.3048 0.2032)
						)
					)
					(width 0)
					(fill yes)
				)
			)
		)
		(pad "2" smd custom
			(at 0 0.4445 90)
			(size 0.1524 0.1524)
			(layers "F.Cu" "F.Mask" "F.Paste")
			(net "GND")
			(options
				(clearance outline)
				(anchor circle)
			)
			(primitives
				(gr_poly
					(pts
						(arc
							(start 0.3048 -0.2032)
							(mid 0.275042 -0.275042)
							(end 0.2032 -0.3048)
						)
						(arc
							(start -0.2032 -0.3048)
							(mid -0.275042 -0.275042)
							(end -0.3048 -0.2032)
						)
						(arc
							(start -0.3048 0.2032)
							(mid -0.275042 0.275042)
							(end -0.2032 0.3048)
						)
						(arc
							(start 0.2032 0.3048)
							(mid 0.275042 0.275042)
							(end 0.3048 0.2032)
						)
					)
					(width 0)
					(fill yes)
				)
			)
		)
	)
	(footprint ""
		(layer "F.Cu")
		(at 177.8 -146.939 -90)
		(property "Reference" "C252"
			(at 0 0 270)
			(layer "F.SilkS")
			(hide yes)
			(effects
				(font
					(size 1.27 1.27)
				)
			)
		)
		(property "Value" "SC10U16V6KX-2GP"
			(at -0.0762 -5.1308 270)
			(unlocked yes)
			(layer "F.Fab")
			(hide yes)
			(effects
				(font
					(size 1.016 1.016)
					(thickness 0.1524)
				)
			)
		)
		(property "Device Type" "C1206H71"
			(at -0.127 -6.6548 270)
			(unlocked yes)
			(layer "F.Fab")
			(hide yes)
			(effects
				(font
					(size 1.016 1.016)
					(thickness 0.1524)
				)
			)
		)
		(duplicate_pad_numbers_are_jumpers no)
		(fp_line
			(start -1.016 2.2352)
			(end -1.016 0.8382)
			(stroke
				(width 0.1524)
				(type default)
			)
			(layer "F.SilkS")
		)
		(fp_line
			(start 1.016 2.2352)
			(end -1.016 2.2352)
			(stroke
				(width 0.1524)
				(type default)
			)
			(layer "F.SilkS")
		)
		(fp_line
			(start 1.016 0.8382)
			(end 1.016 2.2352)
			(stroke
				(width 0.1524)
				(type default)
			)
			(layer "F.SilkS")
		)
		(fp_line
			(start -1.016 -0.8382)
			(end -1.016 -2.2352)
			(stroke
				(width 0.1524)
				(type default)
			)
			(layer "F.SilkS")
		)
		(fp_line
			(start -1.016 -2.2352)
			(end 1.016 -2.2352)
			(stroke
				(width 0.1524)
				(type default)
			)
			(layer "F.SilkS")
		)
		(fp_line
			(start 1.016 -2.2352)
			(end 1.016 -0.8382)
			(stroke
				(width 0.1524)
				(type default)
			)
			(layer "F.SilkS")
		)
		(fp_rect
			(start -1.0922 2.3114)
			(end 1.0922 -2.3114)
			(stroke
				(width 0)
				(type default)
			)
			(fill no)
			(layer "F.CrtYd")
		)
		(fp_poly
			(pts
				(xy 1.0922 -2.3114) (xy 1.0922 2.3114) (xy -1.0922 2.3114) (xy -1.0922 -2.3114)
			)
			(stroke
				(width 0)
				(type default)
			)
			(fill no)
			(layer "F.Fab")
		)
		(pad "1" smd rect
			(at 0 -1.397 270)
			(size 1.651 1.27)
			(layers "F.Cu" "F.Mask" "F.Paste")
			(net "P5V_HDD17")
		)
		(pad "2" smd rect
			(at 0 1.397 270)
			(size 1.651 1.27)
			(layers "F.Cu" "F.Mask" "F.Paste")
			(net "GND")
		)
	)
	(footprint ""
		(layer "F.Cu")
		(at 458.47 -151.892 180)
		(property "Reference" "C317"
			(at 0 0 180)
			(layer "F.SilkS")
			(hide yes)
			(effects
				(font
					(size 1.27 1.27)
				)
			)
		)
		(property "Value" "SC10U16V6KX-2GP"
			(at -0.0762 -5.1308 180)
			(unlocked yes)
			(layer "F.Fab")
			(hide yes)
			(effects
				(font
					(size 1.016 1.016)
					(thickness 0.1524)
				)
			)
		)
		(property "Device Type" "C1206H71"
			(at -0.127 -6.6548 180)
			(unlocked yes)
			(layer "F.Fab")
			(hide yes)
			(effects
				(font
					(size 1.016 1.016)
					(thickness 0.1524)
				)
			)
		)
		(duplicate_pad_numbers_are_jumpers no)
		(fp_line
			(start 1.016 2.2352)
			(end -1.016 2.2352)
			(stroke
				(width 0.1524)
				(type default)
			)
			(layer "F.SilkS")
		)
		(fp_line
			(start 1.016 0.8382)
			(end 1.016 2.2352)
			(stroke
				(width 0.1524)
				(type default)
			)
			(layer "F.SilkS")
		)
		(fp_line
			(start 1.016 -2.2352)
			(end 1.016 -0.8382)
			(stroke
				(width 0.1524)
				(type default)
			)
			(layer "F.SilkS")
		)
		(fp_line
			(start -1.016 2.2352)
			(end -1.016 0.8382)
			(stroke
				(width 0.1524)
				(type default)
			)
			(layer "F.SilkS")
		)
		(fp_line
			(start -1.016 -0.8382)
			(end -1.016 -2.2352)
			(stroke
				(width 0.1524)
				(type default)
			)
			(layer "F.SilkS")
		)
		(fp_line
			(start -1.016 -2.2352)
			(end 1.016 -2.2352)
			(stroke
				(width 0.1524)
				(type default)
			)
			(layer "F.SilkS")
		)
		(fp_rect
			(start -1.0922 2.3114)
			(end 1.0922 -2.3114)
			(stroke
				(width 0)
				(type default)
			)
			(fill no)
			(layer "F.CrtYd")
		)
		(fp_poly
			(pts
				(xy 1.0922 -2.3114) (xy 1.0922 2.3114) (xy -1.0922 2.3114) (xy -1.0922 -2.3114)
			)
			(stroke
				(width 0)
				(type default)
			)
			(fill no)
			(layer "F.Fab")
		)
		(pad "1" smd rect
			(at 0 -1.397 180)
			(size 1.651 1.27)
			(layers "F.Cu" "F.Mask" "F.Paste")
			(net "P5V_HDD22")
		)
		(pad "2" smd rect
			(at 0 1.397 180)
			(size 1.651 1.27)
			(layers "F.Cu" "F.Mask" "F.Paste")
			(net "GND")
		)
	)
	(footprint ""
		(layer "F.Cu")
		(at 263.129522 -363.194346)
		(property "Reference" "C105"
			(at 0 0 0)
			(layer "F.SilkS")
			(hide yes)
			(effects
				(font
					(size 1.27 1.27)
				)
			)
		)
		(property "Value" "SCD1U16V2KX-3GP"
			(at 1.1811 -2.7051 0)
			(unlocked yes)
			(layer "F.Fab")
			(hide yes)
			(effects
				(font
					(size 1.016 1.016)
					(thickness 0.1524)
				)
			)
		)
		(property "Device Type" "C402H22"
			(at 1.1811 -4.2291 0)
			(unlocked yes)
			(layer "F.Fab")
			(hide yes)
			(effects
				(font
					(size 1.016 1.016)
					(thickness 0.1524)
				)
			)
		)
		(duplicate_pad_numbers_are_jumpers no)
		(fp_rect
			(start -0.4318 0.9525)
			(end 0.4318 -0.9525)
			(stroke
				(width 0)
				(type default)
			)
			(fill no)
			(layer "F.CrtYd")
		)
		(fp_rect
			(start -0.4318 0.9525)
			(end 0.4318 -0.9525)
			(stroke
				(width 0)
				(type default)
			)
			(fill no)
			(layer "F.Fab")
		)
		(pad "1" smd custom
			(at 0 -0.4445)
			(size 0.1524 0.1524)
			(layers "F.Cu" "F.Mask" "F.Paste")
			(net "P3V3_IN_BIAS")
			(options
				(clearance outline)
				(anchor circle)
			)
			(primitives
				(gr_poly
					(pts
						(arc
							(start 0.3048 -0.2032)
							(mid 0.275042 -0.275042)
							(end 0.2032 -0.3048)
						)
						(arc
							(start -0.2032 -0.3048)
							(mid -0.275042 -0.275042)
							(end -0.3048 -0.2032)
						)
						(arc
							(start -0.3048 0.2032)
							(mid -0.275042 0.275042)
							(end -0.2032 0.3048)
						)
						(arc
							(start 0.2032 0.3048)
							(mid 0.275042 0.275042)
							(end 0.3048 0.2032)
						)
					)
					(width 0)
					(fill yes)
				)
			)
		)
		(pad "2" smd custom
			(at 0 0.4445)
			(size 0.1524 0.1524)
			(layers "F.Cu" "F.Mask" "F.Paste")
			(net "GND")
			(options
				(clearance outline)
				(anchor circle)
			)
			(primitives
				(gr_poly
					(pts
						(arc
							(start 0.3048 -0.2032)
							(mid 0.275042 -0.275042)
							(end 0.2032 -0.3048)
						)
						(arc
							(start -0.2032 -0.3048)
							(mid -0.275042 -0.275042)
							(end -0.3048 -0.2032)
						)
						(arc
							(start -0.3048 0.2032)
							(mid -0.275042 0.275042)
							(end -0.2032 0.3048)
						)
						(arc
							(start 0.2032 0.3048)
							(mid 0.275042 0.275042)
							(end 0.3048 0.2032)
						)
					)
					(width 0)
					(fill yes)
				)
			)
		)
	)
	(footprint ""
		(layer "F.Cu")
		(at 113.538 -150.622 90)
		(property "Reference" "R416"
			(at 0 0 90)
			(layer "F.SilkS")
			(hide yes)
			(effects
				(font
					(size 1.27 1.27)
				)
			)
		)
		(property "Value" "2R6F-GP"
			(at -0.0508 -4.8514 90)
			(unlocked yes)
			(layer "F.Fab")
			(hide yes)
			(effects
				(font
					(size 1.016 1.016)
					(thickness 0.1524)
				)
			)
		)
		(property "Device Type" "R1206H26"
			(at 0 -6.3754 90)
			(unlocked yes)
			(layer "F.Fab")
			(hide yes)
			(effects
				(font
					(size 1.016 1.016)
					(thickness 0.1524)
				)
			)
		)
		(duplicate_pad_numbers_are_jumpers no)
		(fp_line
			(start 1.016 -2.2352)
			(end 1.016 2.2352)
			(stroke
				(width 0.1524)
				(type default)
			)
			(layer "F.SilkS")
		)
		(fp_line
			(start -1.016 -2.2352)
			(end 1.016 -2.2352)
			(stroke
				(width 0.1524)
				(type default)
			)
			(layer "F.SilkS")
		)
		(fp_line
			(start 1.016 2.2352)
			(end -1.016 2.2352)
			(stroke
				(width 0.1524)
				(type default)
			)
			(layer "F.SilkS")
		)
		(fp_line
			(start -1.016 2.2352)
			(end -1.016 -2.2352)
			(stroke
				(width 0.1524)
				(type default)
			)
			(layer "F.SilkS")
		)
		(fp_rect
			(start -1.0922 2.3114)
			(end 1.0922 -2.3114)
			(stroke
				(width 0)
				(type default)
			)
			(fill no)
			(layer "F.CrtYd")
		)
		(fp_poly
			(pts
				(xy -1.0922 -2.3114) (xy 1.0922 -2.3114) (xy 1.0922 2.3114) (xy -1.0922 2.3114)
			)
			(stroke
				(width 0)
				(type default)
			)
			(fill no)
			(layer "F.Fab")
		)
		(pad "1" smd rect
			(at 0 -1.397 90)
			(size 1.651 1.27)
			(layers "F.Cu" "F.Mask" "F.Paste")
			(net "P12V_HDD15")
		)
		(pad "2" smd rect
			(at 0 1.397 90)
			(size 1.651 1.27)
			(layers "F.Cu" "F.Mask" "F.Paste")
			(net "12V_PRE_15")
		)
	)
	(footprint ""
		(layer "F.Cu")
		(at 127.15875 -18.750026 -90)
		(property "Reference" "VIA56"
			(at 0 0 270)
			(layer "F.SilkS")
			(hide yes)
			(effects
				(font
					(size 1.27 1.27)
				)
			)
		)
		(property "Value" "100OHM-8L-2D36MM-L16-GP"
			(at -3.4036 -0.4572 270)
			(unlocked yes)
			(layer "F.Fab")
			(hide yes)
			(effects
				(font
					(size 1.016 1.016)
					(thickness 0.1524)
				)
			)
		)
		(property "Device Type" "VIA-PCIE-4P-427097"
			(at -3.4036 -1.9812 270)
			(unlocked yes)
			(layer "F.Fab")
			(hide yes)
			(effects
				(font
					(size 1.016 1.016)
					(thickness 0.1524)
				)
			)
		)
		(duplicate_pad_numbers_are_jumpers no)
		(fp_rect
			(start -2.1336 0.4826)
			(end 2.1336 -0.4826)
			(stroke
				(width 0)
				(type default)
			)
			(fill no)
			(layer "F.CrtYd")
		)
		(fp_rect
			(start -2.1336 0.4826)
			(end 2.1336 -0.4826)
			(stroke
				(width 0)
				(type default)
			)
			(fill no)
			(layer "F.Fab")
		)
		(pad "1" thru_hole circle
			(at -1.651 0 270)
			(size 0.508 0.508)
			(drill 0.254)
			(layers "*.Cu" "*.Mask")
			(remove_unused_layers no)
			(net "GND")
			(clearance 0.2286)
			(thermal_gap 0.2286)
		)
		(pad "2" thru_hole circle
			(at -0.635 0 270)
			(size 0.508 0.508)
			(drill 0.254)
			(layers "*.Cu" "*.Mask")
			(remove_unused_layers no)
			(net "PHY_DRV_B_TO_SCC_B_27_DP")
			(clearance 0.2286)
			(thermal_gap 0.2286)
		)
		(pad "3" thru_hole circle
			(at 0.635 0 270)
			(size 0.508 0.508)
			(drill 0.254)
			(layers "*.Cu" "*.Mask")
			(remove_unused_layers no)
			(net "PHY_DRV_B_TO_SCC_B_27_DN")
			(clearance 0.2286)
			(thermal_gap 0.2286)
		)
		(pad "4" thru_hole circle
			(at 1.651 0 270)
			(size 0.508 0.508)
			(drill 0.254)
			(layers "*.Cu" "*.Mask")
			(remove_unused_layers no)
			(net "GND")
			(clearance 0.2286)
			(thermal_gap 0.2286)
		)
	)
)
